(kicad_pcb
	(version 20260206)
	(generator "pcbnew")
	(generator_version "10.0")
	(general
		(thickness 1.6)
		(legacy_teardrops no)
	)
	(paper "A4")
	(title_block
		(title "01162023_DA0F0TEBIF0_F0T_Expander_BD_F_brd_V02_OCP.brd")
		(comment 1 "Grand Teton / footprint 3799 of 9728 (J20), pads 110-179 of 179")
	)
	(layers
		(0 "F.Cu" signal "TOP")
		(4 "In1.Cu" signal "GND")
		(6 "In2.Cu" signal "VCC")
		(8 "In3.Cu" signal "VCC1")
		(10 "In4.Cu" signal "GND1")
		(12 "In5.Cu" signal "IN1")
		(14 "In6.Cu" signal "GND2")
		(16 "In7.Cu" signal "IN2")
		(18 "In8.Cu" signal "GND3")
		(20 "In9.Cu" signal "IN3")
		(22 "In10.Cu" signal "GND4")
		(24 "In11.Cu" signal "IN4")
		(26 "In12.Cu" signal "GND5")
		(28 "In13.Cu" signal "IN5")
		(30 "In14.Cu" signal "GND6")
		(32 "In15.Cu" signal "IN6")
		(34 "In16.Cu" signal "GND7")
		(2 "B.Cu" signal "BOTTOM")
		(9 "F.Adhes" user "F.Adhesive")
		(11 "B.Adhes" user "B.Adhesive")
		(13 "F.Paste" user "Package Geometry/Pastemask Top")
		(15 "B.Paste" user "Package Geometry/Pastemask Bottom")
		(5 "F.SilkS" user "Ref Des/Silkscreen Top")
		(7 "B.SilkS" user "Ref Des/Silkscreen Bottom")
		(1 "F.Mask" user "Board Geometry/Soldermask Top")
		(3 "B.Mask" user "Board Geometry/Soldermask Bottom")
		(17 "Dwgs.User" user "User.Drawings")
		(19 "Cmts.User" user "User.Comments")
		(21 "Eco1.User" user "User.Eco1")
		(23 "Eco2.User" user "User.Eco2")
		(25 "Edge.Cuts" user "Board Geometry/Outline")
		(27 "Margin" user)
		(31 "F.CrtYd" user "Package Geometry/Place Bound Top")
		(29 "B.CrtYd" user "Package Geometry/Place Bound Bottom")
		(35 "F.Fab" user "Ref Des/Assembly Top")
		(33 "B.Fab" user "Ref Des/Assembly Bottom")
	)
	(footprint ""
		(layer "F.Cu")
		(at 47.319946 -127.700024)
		(property "Reference" "J20"
			(at -5.307076 34.685224 90)
			(unlocked yes)
			(layer "F.SilkS")
			(effects
				(font
					(size 0.7874 0.5842)
					(thickness 0.1524)
				)
				(justify left)
			)
		)
		(property "Value" ""
			(at 0 0 0)
			(layer "F.Fab")
			(effects
				(font
					(size 1.27 1.27)
				)
			)
		)
		(duplicate_pad_numbers_are_jumpers no)
		(pad "B38" smd rect
			(at -1.27762 7.14502 270)
			(size 0.3556 1.2192)
			(layers "F.Cu" "F.Mask" "F.Paste")
			(net "GND")
		)
		(pad "B39" smd rect
			(at -1.27762 7.744968 270)
			(size 0.3556 1.2192)
			(layers "F.Cu" "F.Mask" "F.Paste")
			(net "P5E_PEX0_STN1_TX_C_DN<24>")
		)
		(pad "B40" smd rect
			(at -1.27762 8.344916 270)
			(size 0.3556 1.2192)
			(layers "F.Cu" "F.Mask" "F.Paste")
			(net "P5E_PEX0_STN1_TX_C_DP<24>")
		)
		(pad "B41" smd rect
			(at -1.27762 8.945118 270)
			(size 0.3556 1.2192)
			(layers "F.Cu" "F.Mask" "F.Paste")
			(net "GND")
		)
		(pad "B42" smd rect
			(at -1.27762 9.545066 270)
			(size 0.3556 1.2192)
			(layers "F.Cu" "F.Mask" "F.Paste")
			(net "PRSNTB0_NIC0_N")
		)
		(pad "B43" smd rect
			(at -1.27762 14.454886 270)
			(size 0.3556 1.2192)
			(layers "F.Cu" "F.Mask" "F.Paste")
			(net "GND")
		)
		(pad "B44" smd rect
			(at -1.27762 15.055088 270)
			(size 0.3556 1.2192)
			(layers "F.Cu" "F.Mask" "F.Paste")
			(net "P5E_PEX0_STN1_TX_C_DP<23>")
		)
		(pad "B45" smd rect
			(at -1.27762 15.655036 270)
			(size 0.3556 1.2192)
			(layers "F.Cu" "F.Mask" "F.Paste")
			(net "P5E_PEX0_STN1_TX_C_DN<23>")
		)
		(pad "B46" smd rect
			(at -1.27762 16.254984 270)
			(size 0.3556 1.2192)
			(layers "F.Cu" "F.Mask" "F.Paste")
			(net "GND")
		)
		(pad "B47" smd rect
			(at -1.27762 16.854932 270)
			(size 0.3556 1.2192)
			(layers "F.Cu" "F.Mask" "F.Paste")
			(net "P5E_PEX0_STN1_TX_C_DN<22>")
		)
		(pad "B48" smd rect
			(at -1.27762 17.45488 270)
			(size 0.3556 1.2192)
			(layers "F.Cu" "F.Mask" "F.Paste")
			(net "P5E_PEX0_STN1_TX_C_DP<22>")
		)
		(pad "B49" smd rect
			(at -1.27762 18.055082 270)
			(size 0.3556 1.2192)
			(layers "F.Cu" "F.Mask" "F.Paste")
			(net "GND")
		)
		(pad "B50" smd rect
			(at -1.27762 18.65503 270)
			(size 0.3556 1.2192)
			(layers "F.Cu" "F.Mask" "F.Paste")
			(net "P5E_PEX0_STN1_TX_C_DP<21>")
		)
		(pad "B51" smd rect
			(at -1.27762 19.254978 270)
			(size 0.3556 1.2192)
			(layers "F.Cu" "F.Mask" "F.Paste")
			(net "P5E_PEX0_STN1_TX_C_DN<21>")
		)
		(pad "B52" smd rect
			(at -1.27762 19.854926 270)
			(size 0.3556 1.2192)
			(layers "F.Cu" "F.Mask" "F.Paste")
			(net "GND")
		)
		(pad "B53" smd rect
			(at -1.27762 20.455128 270)
			(size 0.3556 1.2192)
			(layers "F.Cu" "F.Mask" "F.Paste")
			(net "P5E_PEX0_STN1_TX_C_DN<20>")
		)
		(pad "B54" smd rect
			(at -1.27762 21.055076 270)
			(size 0.3556 1.2192)
			(layers "F.Cu" "F.Mask" "F.Paste")
			(net "P5E_PEX0_STN1_TX_C_DP<20>")
		)
		(pad "B55" smd rect
			(at -1.27762 21.655024 270)
			(size 0.3556 1.2192)
			(layers "F.Cu" "F.Mask" "F.Paste")
			(net "GND")
		)
		(pad "B56" smd rect
			(at -1.27762 22.254972 270)
			(size 0.3556 1.2192)
			(layers "F.Cu" "F.Mask" "F.Paste")
			(net "P5E_PEX0_STN1_TX_C_DP<19>")
		)
		(pad "B57" smd rect
			(at -1.27762 22.85492 270)
			(size 0.3556 1.2192)
			(layers "F.Cu" "F.Mask" "F.Paste")
			(net "P5E_PEX0_STN1_TX_C_DN<19>")
		)
		(pad "B58" smd rect
			(at -1.27762 23.455122 270)
			(size 0.3556 1.2192)
			(layers "F.Cu" "F.Mask" "F.Paste")
			(net "GND")
		)
		(pad "B59" smd rect
			(at -1.27762 24.05507 270)
			(size 0.3556 1.2192)
			(layers "F.Cu" "F.Mask" "F.Paste")
			(net "P5E_PEX0_STN1_TX_C_DN<18>")
		)
		(pad "B60" smd rect
			(at -1.27762 24.655018 270)
			(size 0.3556 1.2192)
			(layers "F.Cu" "F.Mask" "F.Paste")
			(net "P5E_PEX0_STN1_TX_C_DP<18>")
		)
		(pad "B61" smd rect
			(at -1.27762 25.254966 270)
			(size 0.3556 1.2192)
			(layers "F.Cu" "F.Mask" "F.Paste")
			(net "GND")
		)
		(pad "B62" smd rect
			(at -1.27762 25.854914 270)
			(size 0.3556 1.2192)
			(layers "F.Cu" "F.Mask" "F.Paste")
			(net "P5E_PEX0_STN1_TX_C_DP<17>")
		)
		(pad "B63" smd rect
			(at -1.27762 26.455116 270)
			(size 0.3556 1.2192)
			(layers "F.Cu" "F.Mask" "F.Paste")
			(net "P5E_PEX0_STN1_TX_C_DN<17>")
		)
		(pad "B64" smd rect
			(at -1.27762 27.055064 270)
			(size 0.3556 1.2192)
			(layers "F.Cu" "F.Mask" "F.Paste")
			(net "GND")
		)
		(pad "B65" smd rect
			(at -1.27762 27.655012 270)
			(size 0.3556 1.2192)
			(layers "F.Cu" "F.Mask" "F.Paste")
			(net "P5E_PEX0_STN1_TX_C_DN<16>")
		)
		(pad "B66" smd rect
			(at -1.27762 28.25496 270)
			(size 0.3556 1.2192)
			(layers "F.Cu" "F.Mask" "F.Paste")
			(net "P5E_PEX0_STN1_TX_C_DP<16>")
		)
		(pad "B67" smd rect
			(at -1.27762 28.854908 270)
			(size 0.3556 1.2192)
			(layers "F.Cu" "F.Mask" "F.Paste")
			(net "GND")
		)
		(pad "B68" smd rect
			(at -1.27762 29.45511 270)
			(size 0.3556 1.2192)
			(layers "F.Cu" "F.Mask" "F.Paste")
			(net "Net_2581")
		)
		(pad "B69" smd rect
			(at -1.27762 30.055058 270)
			(size 0.3556 1.2192)
			(layers "F.Cu" "F.Mask" "F.Paste")
			(net "Net_2582")
		)
		(pad "B70" smd rect
			(at -1.27762 30.655006 270)
			(size 0.3556 1.2192)
			(layers "F.Cu" "F.Mask" "F.Paste")
			(net "PRSNTB3_NIC0_N")
		)
		(pad "G1" thru_hole oval
			(at 1.022604 -34.034984 270)
			(size 1.6256 3.4798)
			(drill oval 1.1176 2.4638)
			(layers "*.Cu" "*.Mask")
			(remove_unused_layers no)
			(net "GND")
			(clearance 0.127)
			(thermal_gap 0.127)
		)
		(pad "G2" thru_hole oval
			(at 1.022604 -20.625054 270)
			(size 1.6256 3.4798)
			(drill oval 1.1176 2.4638)
			(layers "*.Cu" "*.Mask")
			(remove_unused_layers no)
			(net "GND")
			(clearance 0.127)
			(thermal_gap 0.127)
		)
		(pad "G3" thru_hole oval
			(at 1.022604 -0.255016 270)
			(size 1.6256 3.4798)
			(drill oval 1.1176 2.4638)
			(layers "*.Cu" "*.Mask")
			(remove_unused_layers no)
			(net "GND")
			(clearance 0.127)
			(thermal_gap 0.127)
		)
		(pad "G4" thru_hole oval
			(at 1.022604 12.005056 270)
			(size 1.6256 3.4798)
			(drill oval 1.1176 2.4638)
			(layers "*.Cu" "*.Mask")
			(remove_unused_layers no)
			(net "GND")
			(clearance 0.127)
			(thermal_gap 0.127)
		)
		(pad "G5" thru_hole oval
			(at 1.022604 34.034984 270)
			(size 1.5748 3.4798)
			(drill oval 1.1176 2.4638)
			(layers "*.Cu" "*.Mask")
			(remove_unused_layers no)
			(net "GND")
			(clearance 0.1524)
			(thermal_gap 0.1524)
		)
		(pad "G6" thru_hole circle
			(at -3.16738 -20.625054)
			(size 1.6256 1.6256)
			(drill 1.1176)
			(layers "*.Cu" "*.Mask")
			(remove_unused_layers no)
			(net "GND")
			(clearance 0)
		)
		(pad "G7" thru_hole circle
			(at -3.16738 12.005056)
			(size 1.6256 1.6256)
			(drill 1.1176)
			(layers "*.Cu" "*.Mask")
			(remove_unused_layers no)
			(net "GND")
			(clearance 0)
		)
		(pad "G8" thru_hole circle
			(at 4.20243 -20.625054)
			(size 1.6256 1.6256)
			(drill 1.1176)
			(layers "*.Cu" "*.Mask")
			(remove_unused_layers no)
			(net "GND")
			(clearance 0)
		)
		(pad "G9" thru_hole circle
			(at 4.20243 12.005056)
			(size 1.6256 1.6256)
			(drill 1.1176)
			(layers "*.Cu" "*.Mask")
			(remove_unused_layers no)
			(net "GND")
			(clearance 0)
		)
		(pad "OA1" smd rect
			(at 3.322574 -30.660086 270)
			(size 0.3556 1.2192)
			(layers "F.Cu" "F.Mask" "F.Paste")
			(net "RST_NIC0_PERST2_R_N")
		)
		(pad "OA2" smd rect
			(at 3.322574 -30.059884 270)
			(size 0.3556 1.2192)
			(layers "F.Cu" "F.Mask" "F.Paste")
			(net "RST_NIC0_PERST3_R_N")
		)
		(pad "OA3" smd rect
			(at 3.322574 -29.459936 270)
			(size 0.3556 1.2192)
			(layers "F.Cu" "F.Mask" "F.Paste")
			(net "Net_2585")
		)
		(pad "OA4" smd rect
			(at 3.322574 -28.859988 270)
			(size 0.3556 1.2192)
			(layers "F.Cu" "F.Mask" "F.Paste")
			(net "NIC0_RBT_ARB_IN")
		)
		(pad "OA5" smd rect
			(at 3.322574 -28.26004 270)
			(size 0.3556 1.2192)
			(layers "F.Cu" "F.Mask" "F.Paste")
			(net "NIC0_RBT_ARB_OUT")
		)
		(pad "OA6" smd rect
			(at 3.322574 -27.660092 270)
			(size 0.3556 1.2192)
			(layers "F.Cu" "F.Mask" "F.Paste")
			(net "NIC0_SLOT_ID1")
		)
		(pad "OA7" smd rect
			(at 3.322574 -27.05989 270)
			(size 0.3556 1.2192)
			(layers "F.Cu" "F.Mask" "F.Paste")
			(net "NCSI_NIC0_TX_EN")
		)
		(pad "OA8" smd rect
			(at 3.322574 -26.459942 270)
			(size 0.3556 1.2192)
			(layers "F.Cu" "F.Mask" "F.Paste")
			(net "NCSI_NIC0_TXD1")
		)
		(pad "OA9" smd rect
			(at 3.322574 -25.859994 270)
			(size 0.3556 1.2192)
			(layers "F.Cu" "F.Mask" "F.Paste")
			(net "NCSI_NIC0_TXD0")
		)
		(pad "OA10" smd rect
			(at 3.322574 -25.260046 270)
			(size 0.3556 1.2192)
			(layers "F.Cu" "F.Mask" "F.Paste")
			(net "GND")
		)
		(pad "OA11" smd rect
			(at 3.322574 -24.660098 270)
			(size 0.3556 1.2192)
			(layers "F.Cu" "F.Mask" "F.Paste")
			(net "Net_2577")
		)
		(pad "OA12" smd rect
			(at 3.322574 -24.059896 270)
			(size 0.3556 1.2192)
			(layers "F.Cu" "F.Mask" "F.Paste")
			(net "Net_2580")
		)
		(pad "OA13" smd rect
			(at 3.322574 -23.459948 270)
			(size 0.3556 1.2192)
			(layers "F.Cu" "F.Mask" "F.Paste")
			(net "GND")
		)
		(pad "OA14" smd rect
			(at 3.322574 -22.86 270)
			(size 0.3556 1.2192)
			(layers "F.Cu" "F.Mask" "F.Paste")
			(net "CLK_50M_NIC0_RBT_REF")
		)
		(pad "OB1" smd rect
			(at -1.27762 -30.660086 270)
			(size 0.3556 1.2192)
			(layers "F.Cu" "F.Mask" "F.Paste")
			(net "PWRGD_NIC0_PWR_GOOD")
		)
		(pad "OB2" smd rect
			(at -1.27762 -30.059884 270)
			(size 0.3556 1.2192)
			(layers "F.Cu" "F.Mask" "F.Paste")
			(net "NIC0_MAIN_PWR_EN_R")
		)
		(pad "OB3" smd rect
			(at -1.27762 -29.459936 270)
			(size 0.3556 1.2192)
			(layers "F.Cu" "F.Mask" "F.Paste")
			(net "NIC0_LD_N")
		)
		(pad "OB4" smd rect
			(at -1.27762 -28.859988 270)
			(size 0.3556 1.2192)
			(layers "F.Cu" "F.Mask" "F.Paste")
			(net "NIC0_DATA_IN")
		)
		(pad "OB5" smd rect
			(at -1.27762 -28.26004 270)
			(size 0.3556 1.2192)
			(layers "F.Cu" "F.Mask" "F.Paste")
			(net "NIC0_DATA_OUT")
		)
		(pad "OB6" smd rect
			(at -1.27762 -27.660092 270)
			(size 0.3556 1.2192)
			(layers "F.Cu" "F.Mask" "F.Paste")
			(net "NIC0_CLK")
		)
		(pad "OB7" smd rect
			(at -1.27762 -27.05989 270)
			(size 0.3556 1.2192)
			(layers "F.Cu" "F.Mask" "F.Paste")
			(net "NIC0_SLOT_ID0")
		)
		(pad "OB8" smd rect
			(at -1.27762 -26.459942 270)
			(size 0.3556 1.2192)
			(layers "F.Cu" "F.Mask" "F.Paste")
			(net "NCSI_NIC0_RXD1")
		)
		(pad "OB9" smd rect
			(at -1.27762 -25.859994 270)
			(size 0.3556 1.2192)
			(layers "F.Cu" "F.Mask" "F.Paste")
			(net "NCSI_NIC0_RXD0")
		)
		(pad "OB10" smd rect
			(at -1.27762 -25.260046 270)
			(size 0.3556 1.2192)
			(layers "F.Cu" "F.Mask" "F.Paste")
			(net "GND")
		)
		(pad "OB11" smd rect
			(at -1.27762 -24.660098 270)
			(size 0.3556 1.2192)
			(layers "F.Cu" "F.Mask" "F.Paste")
			(net "Net_2576")
		)
		(pad "OB12" smd rect
			(at -1.27762 -24.059896 270)
			(size 0.3556 1.2192)
			(layers "F.Cu" "F.Mask" "F.Paste")
			(net "Net_2579")
		)
		(pad "OB13" smd rect
			(at -1.27762 -23.459948 270)
			(size 0.3556 1.2192)
			(layers "F.Cu" "F.Mask" "F.Paste")
			(net "GND")
		)
		(pad "OB14" smd rect
			(at -1.27762 -22.86 270)
			(size 0.3556 1.2192)
			(layers "F.Cu" "F.Mask" "F.Paste")
			(net "NCSI_NIC0_CRS_DV")
		)
	)
)
